(kicad_pcb
	(version 20260206)
	(generator "pcbnew")
	(generator_version "10.0")
	(general
		(thickness 1.6)
		(legacy_teardrops no)
	)
	(paper "A4")
	(title_block
		(title "03242023_DA0F0TMBIJ0_F0T_Motherboard_J_brd_V01_OCP.brd")
		(comment 1 "Grand Teton / footprints 3653-3657 of 6105")
	)
	(layers
		(0 "F.Cu" signal "TOP")
		(4 "In1.Cu" signal "GND")
		(6 "In2.Cu" signal "IN1")
		(8 "In3.Cu" signal "GND1")
		(10 "In4.Cu" signal "IN2")
		(12 "In5.Cu" signal "GND2")
		(14 "In6.Cu" signal "IN3")
		(16 "In7.Cu" signal "GND3")
		(18 "In8.Cu" signal "VCC")
		(20 "In9.Cu" signal "VCC1")
		(22 "In10.Cu" signal "GND4")
		(24 "In11.Cu" signal "IN4")
		(26 "In12.Cu" signal "GND5")
		(28 "In13.Cu" signal "IN5")
		(30 "In14.Cu" signal "GND6")
		(32 "In15.Cu" signal "IN6")
		(34 "In16.Cu" signal "GND7")
		(2 "B.Cu" signal "BOTTOM")
		(9 "F.Adhes" user "F.Adhesive")
		(11 "B.Adhes" user "B.Adhesive")
		(13 "F.Paste" user "Package Geometry/Pastemask Top")
		(15 "B.Paste" user "Package Geometry/Pastemask Bottom")
		(5 "F.SilkS" user "Ref Des/Silkscreen Top")
		(7 "B.SilkS" user "Ref Des/Silkscreen Bottom")
		(1 "F.Mask" user "Board Geometry/Soldermask Top")
		(3 "B.Mask" user "Board Geometry/Soldermask Bottom")
		(17 "Dwgs.User" user "User.Drawings")
		(19 "Cmts.User" user "User.Comments")
		(21 "Eco1.User" user "User.Eco1")
		(23 "Eco2.User" user "User.Eco2")
		(25 "Edge.Cuts" user "Board Geometry/Outline")
		(27 "Margin" user)
		(31 "F.CrtYd" user "Package Geometry/Place Bound Top")
		(29 "B.CrtYd" user "Package Geometry/Place Bound Bottom")
		(35 "F.Fab" user "Ref Des/Assembly Top")
		(33 "B.Fab" user "Ref Des/Assembly Bottom")
	)
	(footprint ""
		(layer "F.Cu")
		(at 121.251472 -357.11638 90)
		(property "Reference" "PC1266"
			(at 0 0 90)
			(layer "F.SilkS")
			(hide yes)
			(effects
				(font
					(size 1.27 1.27)
				)
			)
		)
		(property "Value" ""
			(at 0 0 90)
			(layer "F.Fab")
			(effects
				(font
					(size 1.27 1.27)
				)
			)
		)
		(duplicate_pad_numbers_are_jumpers no)
		(fp_line
			(start 0.7874 -0.4064)
			(end 0.7874 0.4064)
			(stroke
				(width 0.1524)
				(type default)
			)
			(layer "F.SilkS")
		)
		(fp_line
			(start -0.7874 -0.4064)
			(end 0.7874 -0.4064)
			(stroke
				(width 0.1524)
				(type default)
			)
			(layer "F.SilkS")
		)
		(fp_line
			(start 0.7874 0.4064)
			(end -0.7874 0.4064)
			(stroke
				(width 0.1524)
				(type default)
			)
			(layer "F.SilkS")
		)
		(fp_line
			(start -0.7874 0.4064)
			(end -0.7874 -0.4064)
			(stroke
				(width 0.1524)
				(type default)
			)
			(layer "F.SilkS")
		)
		(fp_line
			(start -0.12065 -0.305054)
			(end -0.12065 -0.2794)
			(stroke
				(width 0.1)
				(type default)
			)
			(layer "F.Fab")
		)
		(fp_line
			(start -0.67945 -0.305054)
			(end -0.12065 -0.305054)
			(stroke
				(width 0.1)
				(type default)
			)
			(layer "F.Fab")
		)
		(fp_line
			(start 0.67945 -0.3048)
			(end 0.67945 0.3048)
			(stroke
				(width 0.1)
				(type default)
			)
			(layer "F.Fab")
		)
		(fp_line
			(start 0.12065 -0.3048)
			(end 0.67945 -0.3048)
			(stroke
				(width 0.1)
				(type default)
			)
			(layer "F.Fab")
		)
		(fp_line
			(start 0.12065 -0.2794)
			(end 0.12065 -0.3048)
			(stroke
				(width 0.1)
				(type default)
			)
			(layer "F.Fab")
		)
		(fp_line
			(start -0.12065 -0.2794)
			(end 0.12065 -0.2794)
			(stroke
				(width 0.1)
				(type default)
			)
			(layer "F.Fab")
		)
		(fp_line
			(start 0.120396 0.2794)
			(end -0.12065 0.2794)
			(stroke
				(width 0.1)
				(type default)
			)
			(layer "F.Fab")
		)
		(fp_line
			(start -0.12065 0.2794)
			(end -0.12065 0.3048)
			(stroke
				(width 0.1)
				(type default)
			)
			(layer "F.Fab")
		)
		(fp_line
			(start 0.67945 0.3048)
			(end 0.120396 0.3048)
			(stroke
				(width 0.1)
				(type default)
			)
			(layer "F.Fab")
		)
		(fp_line
			(start 0.120396 0.3048)
			(end 0.120396 0.2794)
			(stroke
				(width 0.1)
				(type default)
			)
			(layer "F.Fab")
		)
		(fp_line
			(start -0.12065 0.3048)
			(end -0.67945 0.3048)
			(stroke
				(width 0.1)
				(type default)
			)
			(layer "F.Fab")
		)
		(fp_line
			(start -0.67945 0.3048)
			(end -0.67945 -0.305054)
			(stroke
				(width 0.1)
				(type default)
			)
			(layer "F.Fab")
		)
		(pad "1" smd circle
			(at -0.40005 0 90)
			(size 0 0)
			(layers "F.Cu" "F.Mask" "F.Paste")
			(net "PVPP_HBM_CPU1_FB")
		)
		(pad "2" smd circle
			(at 0.40005 0 90)
			(size 0 0)
			(layers "F.Cu" "F.Mask" "F.Paste")
			(net "SH_PVPP_HBM_CPU1_P")
		)
	)
	(footprint ""
		(layer "F.Cu")
		(at 378.099574 -4.696206 180)
		(property "Reference" "J63"
			(at -4.451096 -1.140206 90)
			(unlocked yes)
			(layer "F.SilkS")
			(effects
				(font
					(size 0.7874 0.5842)
					(thickness 0.1524)
				)
				(justify left)
			)
		)
		(property "Value" ""
			(at 0 0 180)
			(layer "F.Fab")
			(effects
				(font
					(size 1.27 1.27)
				)
			)
		)
		(duplicate_pad_numbers_are_jumpers no)
		(fp_line
			(start 1.2192 2.1082)
			(end -1.2192 2.1082)
			(stroke
				(width 0.1524)
				(type default)
			)
			(layer "F.SilkS")
		)
		(fp_line
			(start 1.2192 -2.1082)
			(end 1.2192 2.1082)
			(stroke
				(width 0.1524)
				(type default)
			)
			(layer "F.SilkS")
		)
		(fp_line
			(start -1.2192 2.1082)
			(end -1.2192 -2.1082)
			(stroke
				(width 0.1524)
				(type default)
			)
			(layer "F.SilkS")
		)
		(fp_line
			(start -1.2192 -2.1082)
			(end 1.2192 -2.1082)
			(stroke
				(width 0.1524)
				(type default)
			)
			(layer "F.SilkS")
		)
		(pad "" np_thru_hole circle
			(at -2.8829 -1.27 90)
			(size 1.0414 1.0414)
			(drill 1.0414)
			(layers "*.Cu" "*.Mask")
			(clearance 0.381)
			(thermal_gap 0.381)
		)
		(pad "" np_thru_hole circle
			(at -2.8829 1.27 90)
			(size 1.0414 1.0414)
			(drill 1.0414)
			(layers "*.Cu" "*.Mask")
			(clearance 0.381)
			(thermal_gap 0.381)
		)
		(pad "" np_thru_hole circle
			(at 3.4671 -1.27 90)
			(size 1.0414 1.0414)
			(drill 1.0414)
			(layers "*.Cu" "*.Mask")
			(clearance 0.381)
			(thermal_gap 0.381)
		)
		(pad "" np_thru_hole circle
			(at 3.4671 1.27 90)
			(size 1.0414 1.0414)
			(drill 1.0414)
			(layers "*.Cu" "*.Mask")
			(clearance 0.381)
			(thermal_gap 0.381)
		)
		(pad "1" smd rect
			(at 0.8255 -0.249936 90)
			(size 0.3048 0.508)
			(layers "F.Cu" "F.Mask" "F.Paste")
			(net "DELTA_L_85_5INCH_TOP_DP")
		)
		(pad "2" smd rect
			(at 0.8255 0.249936 90)
			(size 0.3048 0.508)
			(layers "F.Cu" "F.Mask" "F.Paste")
			(net "DELTA_L_85_5INCH_TOP_DN")
		)
		(pad "3" smd circle
			(at 0 0 180)
			(size 0 0)
			(layers "F.Cu" "F.Mask" "F.Paste")
			(net "DELTA_L_GND_1")
		)
		(zone
			(layer "F.Cu")
			(hatch none 0.5)
			(connect_pads
				(clearance 0)
			)
			(min_thickness 0.25)
			(keepout
				(tracks not_allowed)
				(vias allowed)
				(pads allowed)
				(copperpour not_allowed)
				(footprints allowed)
			)
			(placement
				(enabled no)
				(sheetname "")
			)
			(fill
				(thermal_gap 0.5)
				(thermal_bridge_width 0.5)
				(island_removal_mode 0)
			)
			(polygon
				(pts
					(xy 376.981974 -4.147566) (xy 376.981974 -4.24307) (xy 377.578874 -4.24307) (xy 377.578874 -4.64947)
					(xy 376.981974 -4.64947) (xy 376.981974 -4.742942) (xy 377.578874 -4.742942) (xy 377.578874 -5.149342)
					(xy 376.981974 -5.149342) (xy 376.981974 -5.244846) (xy 377.680474 -5.244846) (xy 377.680474 -4.147566)
				)
			)
		)
		(zone
			(layers "F.Cu" "B.Cu" "In1.Cu" "In2.Cu" "In3.Cu" "In4.Cu" "In5.Cu" "In6.Cu"
				"In7.Cu" "In8.Cu" "In9.Cu" "In10.Cu" "In11.Cu" "In12.Cu" "In13.Cu" "In14.Cu"
				"In15.Cu" "In16.Cu"
			)
			(hatch none 0.5)
			(connect_pads
				(clearance 0)
			)
			(min_thickness 0.25)
			(keepout
				(tracks not_allowed)
				(vias allowed)
				(pads allowed)
				(copperpour not_allowed)
				(footprints allowed)
			)
			(placement
				(enabled no)
				(sheetname "")
			)
			(fill
				(thermal_gap 0.5)
				(thermal_bridge_width 0.5)
				(island_removal_mode 0)
			)
			(polygon
				(pts
					(arc
						(start 375.559574 -5.966206)
						(mid 373.705374 -5.966206)
						(end 375.559574 -5.966206)
					)
				)
			)
		)
		(zone
			(layers "F.Cu" "B.Cu" "In1.Cu" "In2.Cu" "In3.Cu" "In4.Cu" "In5.Cu" "In6.Cu"
				"In7.Cu" "In8.Cu" "In9.Cu" "In10.Cu" "In11.Cu" "In12.Cu" "In13.Cu" "In14.Cu"
				"In15.Cu" "In16.Cu"
			)
			(hatch none 0.5)
			(connect_pads
				(clearance 0)
			)
			(min_thickness 0.25)
			(keepout
				(tracks not_allowed)
				(vias allowed)
				(pads allowed)
				(copperpour not_allowed)
				(footprints allowed)
			)
			(placement
				(enabled no)
				(sheetname "")
			)
			(fill
				(thermal_gap 0.5)
				(thermal_bridge_width 0.5)
				(island_removal_mode 0)
			)
			(polygon
				(pts
					(arc
						(start 375.559574 -3.426206)
						(mid 373.705374 -3.426206)
						(end 375.559574 -3.426206)
					)
				)
			)
		)
		(zone
			(layers "F.Cu" "B.Cu" "In1.Cu" "In2.Cu" "In3.Cu" "In4.Cu" "In5.Cu" "In6.Cu"
				"In7.Cu" "In8.Cu" "In9.Cu" "In10.Cu" "In11.Cu" "In12.Cu" "In13.Cu" "In14.Cu"
				"In15.Cu" "In16.Cu"
			)
			(hatch none 0.5)
			(connect_pads
				(clearance 0)
			)
			(min_thickness 0.25)
			(keepout
				(tracks not_allowed)
				(vias allowed)
				(pads allowed)
				(copperpour not_allowed)
				(footprints allowed)
			)
			(placement
				(enabled no)
				(sheetname "")
			)
			(fill
				(thermal_gap 0.5)
				(thermal_bridge_width 0.5)
				(island_removal_mode 0)
			)
			(polygon
				(pts
					(arc
						(start 381.909574 -5.966206)
						(mid 380.055374 -5.966206)
						(end 381.909574 -5.966206)
					)
				)
			)
		)
		(zone
			(layers "F.Cu" "B.Cu" "In1.Cu" "In2.Cu" "In3.Cu" "In4.Cu" "In5.Cu" "In6.Cu"
				"In7.Cu" "In8.Cu" "In9.Cu" "In10.Cu" "In11.Cu" "In12.Cu" "In13.Cu" "In14.Cu"
				"In15.Cu" "In16.Cu"
			)
			(hatch none 0.5)
			(connect_pads
				(clearance 0)
			)
			(min_thickness 0.25)
			(keepout
				(tracks not_allowed)
				(vias allowed)
				(pads allowed)
				(copperpour not_allowed)
				(footprints allowed)
			)
			(placement
				(enabled no)
				(sheetname "")
			)
			(fill
				(thermal_gap 0.5)
				(thermal_bridge_width 0.5)
				(island_removal_mode 0)
			)
			(polygon
				(pts
					(arc
						(start 381.909574 -3.426206)
						(mid 380.055374 -3.426206)
						(end 381.909574 -3.426206)
					)
				)
			)
		)
	)
	(footprint ""
		(layer "F.Cu")
		(at 31.29788 -431.891948)
		(property "Reference" "R3515"
			(at 0 0 0)
			(layer "F.SilkS")
			(hide yes)
			(effects
				(font
					(size 1.27 1.27)
				)
			)
		)
		(property "Value" ""
			(at 0 0 0)
			(layer "F.Fab")
			(effects
				(font
					(size 1.27 1.27)
				)
			)
		)
		(duplicate_pad_numbers_are_jumpers no)
		(fp_line
			(start -0.7874 -0.4064)
			(end 0.7874 -0.4064)
			(stroke
				(width 0.1524)
				(type default)
			)
			(layer "F.SilkS")
		)
		(fp_line
			(start -0.7874 0.4064)
			(end -0.7874 -0.4064)
			(stroke
				(width 0.1524)
				(type default)
			)
			(layer "F.SilkS")
		)
		(fp_line
			(start 0.7874 -0.4064)
			(end 0.7874 0.4064)
			(stroke
				(width 0.1524)
				(type default)
			)
			(layer "F.SilkS")
		)
		(fp_line
			(start 0.7874 0.4064)
			(end -0.7874 0.4064)
			(stroke
				(width 0.1524)
				(type default)
			)
			(layer "F.SilkS")
		)
		(fp_line
			(start -0.67945 -0.305054)
			(end -0.12065 -0.305054)
			(stroke
				(width 0.1)
				(type default)
			)
			(layer "F.Fab")
		)
		(fp_line
			(start -0.67945 0.3048)
			(end -0.67945 -0.305054)
			(stroke
				(width 0.1)
				(type default)
			)
			(layer "F.Fab")
		)
		(fp_line
			(start -0.12065 -0.305054)
			(end -0.12065 -0.2794)
			(stroke
				(width 0.1)
				(type default)
			)
			(layer "F.Fab")
		)
		(fp_line
			(start -0.12065 -0.2794)
			(end 0.12065 -0.2794)
			(stroke
				(width 0.1)
				(type default)
			)
			(layer "F.Fab")
		)
		(fp_line
			(start -0.12065 0.2794)
			(end -0.12065 0.3048)
			(stroke
				(width 0.1)
				(type default)
			)
			(layer "F.Fab")
		)
		(fp_line
			(start -0.12065 0.3048)
			(end -0.67945 0.3048)
			(stroke
				(width 0.1)
				(type default)
			)
			(layer "F.Fab")
		)
		(fp_line
			(start 0.120396 0.2794)
			(end -0.12065 0.2794)
			(stroke
				(width 0.1)
				(type default)
			)
			(layer "F.Fab")
		)
		(fp_line
			(start 0.120396 0.3048)
			(end 0.120396 0.2794)
			(stroke
				(width 0.1)
				(type default)
			)
			(layer "F.Fab")
		)
		(fp_line
			(start 0.12065 -0.3048)
			(end 0.67945 -0.3048)
			(stroke
				(width 0.1)
				(type default)
			)
			(layer "F.Fab")
		)
		(fp_line
			(start 0.12065 -0.2794)
			(end 0.12065 -0.3048)
			(stroke
				(width 0.1)
				(type default)
			)
			(layer "F.Fab")
		)
		(fp_line
			(start 0.67945 -0.3048)
			(end 0.67945 0.3048)
			(stroke
				(width 0.1)
				(type default)
			)
			(layer "F.Fab")
		)
		(fp_line
			(start 0.67945 0.3048)
			(end 0.120396 0.3048)
			(stroke
				(width 0.1)
				(type default)
			)
			(layer "F.Fab")
		)
		(pad "1" smd circle
			(at -0.40005 0)
			(size 0 0)
			(layers "F.Cu" "F.Mask" "F.Paste")
			(net "FM_SWB_PWR_EN_R1_BUF")
		)
		(pad "2" smd circle
			(at 0.40005 0)
			(size 0 0)
			(layers "F.Cu" "F.Mask" "F.Paste")
			(net "FM_SWB_PWR_EN_R_BUF")
		)
	)
	(footprint ""
		(layer "F.Cu")
		(at 20.8026 -410.7942 90)
		(property "Reference" "R4734"
			(at 0 0 90)
			(layer "F.SilkS")
			(hide yes)
			(effects
				(font
					(size 1.27 1.27)
				)
			)
		)
		(property "Value" ""
			(at 0 0 90)
			(layer "F.Fab")
			(effects
				(font
					(size 1.27 1.27)
				)
			)
		)
		(duplicate_pad_numbers_are_jumpers no)
		(fp_line
			(start 0.7874 -0.4064)
			(end 0.7874 0.4064)
			(stroke
				(width 0.1524)
				(type default)
			)
			(layer "F.SilkS")
		)
		(fp_line
			(start -0.7874 -0.4064)
			(end 0.7874 -0.4064)
			(stroke
				(width 0.1524)
				(type default)
			)
			(layer "F.SilkS")
		)
		(fp_line
			(start 0.7874 0.4064)
			(end -0.7874 0.4064)
			(stroke
				(width 0.1524)
				(type default)
			)
			(layer "F.SilkS")
		)
		(fp_line
			(start -0.7874 0.4064)
			(end -0.7874 -0.4064)
			(stroke
				(width 0.1524)
				(type default)
			)
			(layer "F.SilkS")
		)
		(fp_line
			(start -0.12065 -0.305054)
			(end -0.12065 -0.2794)
			(stroke
				(width 0.1)
				(type default)
			)
			(layer "F.Fab")
		)
		(fp_line
			(start -0.67945 -0.305054)
			(end -0.12065 -0.305054)
			(stroke
				(width 0.1)
				(type default)
			)
			(layer "F.Fab")
		)
		(fp_line
			(start 0.67945 -0.3048)
			(end 0.67945 0.3048)
			(stroke
				(width 0.1)
				(type default)
			)
			(layer "F.Fab")
		)
		(fp_line
			(start 0.12065 -0.3048)
			(end 0.67945 -0.3048)
			(stroke
				(width 0.1)
				(type default)
			)
			(layer "F.Fab")
		)
		(fp_line
			(start 0.12065 -0.2794)
			(end 0.12065 -0.3048)
			(stroke
				(width 0.1)
				(type default)
			)
			(layer "F.Fab")
		)
		(fp_line
			(start -0.12065 -0.2794)
			(end 0.12065 -0.2794)
			(stroke
				(width 0.1)
				(type default)
			)
			(layer "F.Fab")
		)
		(fp_line
			(start 0.120396 0.2794)
			(end -0.12065 0.2794)
			(stroke
				(width 0.1)
				(type default)
			)
			(layer "F.Fab")
		)
		(fp_line
			(start -0.12065 0.2794)
			(end -0.12065 0.3048)
			(stroke
				(width 0.1)
				(type default)
			)
			(layer "F.Fab")
		)
		(fp_line
			(start 0.67945 0.3048)
			(end 0.120396 0.3048)
			(stroke
				(width 0.1)
				(type default)
			)
			(layer "F.Fab")
		)
		(fp_line
			(start 0.120396 0.3048)
			(end 0.120396 0.2794)
			(stroke
				(width 0.1)
				(type default)
			)
			(layer "F.Fab")
		)
		(fp_line
			(start -0.12065 0.3048)
			(end -0.67945 0.3048)
			(stroke
				(width 0.1)
				(type default)
			)
			(layer "F.Fab")
		)
		(fp_line
			(start -0.67945 0.3048)
			(end -0.67945 -0.305054)
			(stroke
				(width 0.1)
				(type default)
			)
			(layer "F.Fab")
		)
		(pad "1" smd circle
			(at -0.40005 0 90)
			(size 0 0)
			(layers "F.Cu" "F.Mask" "F.Paste")
			(net "PRSNT_CABLE_GPU_B3_ISO_N")
		)
		(pad "2" smd circle
			(at 0.40005 0 90)
			(size 0 0)
			(layers "F.Cu" "F.Mask" "F.Paste")
			(net "PRSNT_CABLE_GPU_B3_ISO_R1_N")
		)
	)
	(footprint ""
		(layer "F.Cu")
		(at 104.13492 -354.445062 -90)
		(property "Reference" "C2446"
			(at 0 0 270)
			(layer "F.SilkS")
			(hide yes)
			(effects
				(font
					(size 1.27 1.27)
				)
			)
		)
		(property "Value" ""
			(at 0 0 270)
			(layer "F.Fab")
			(effects
				(font
					(size 1.27 1.27)
				)
			)
		)
		(duplicate_pad_numbers_are_jumpers no)
		(fp_line
			(start -0.7874 0.4064)
			(end -0.7874 -0.4064)
			(stroke
				(width 0.1524)
				(type default)
			)
			(layer "F.SilkS")
		)
		(fp_line
			(start 0.7874 0.4064)
			(end -0.7874 0.4064)
			(stroke
				(width 0.1524)
				(type default)
			)
			(layer "F.SilkS")
		)
		(fp_line
			(start -0.7874 -0.4064)
			(end 0.7874 -0.4064)
			(stroke
				(width 0.1524)
				(type default)
			)
			(layer "F.SilkS")
		)
		(fp_line
			(start 0.7874 -0.4064)
			(end 0.7874 0.4064)
			(stroke
				(width 0.1524)
				(type default)
			)
			(layer "F.SilkS")
		)
		(fp_line
			(start -0.67945 0.3048)
			(end -0.67945 -0.305054)
			(stroke
				(width 0.1)
				(type default)
			)
			(layer "F.Fab")
		)
		(fp_line
			(start -0.12065 0.3048)
			(end -0.67945 0.3048)
			(stroke
				(width 0.1)
				(type default)
			)
			(layer "F.Fab")
		)
		(fp_line
			(start 0.120396 0.3048)
			(end 0.120396 0.2794)
			(stroke
				(width 0.1)
				(type default)
			)
			(layer "F.Fab")
		)
		(fp_line
			(start 0.67945 0.3048)
			(end 0.120396 0.3048)
			(stroke
				(width 0.1)
				(type default)
			)
			(layer "F.Fab")
		)
		(fp_line
			(start -0.12065 0.2794)
			(end -0.12065 0.3048)
			(stroke
				(width 0.1)
				(type default)
			)
			(layer "F.Fab")
		)
		(fp_line
			(start 0.120396 0.2794)
			(end -0.12065 0.2794)
			(stroke
				(width 0.1)
				(type default)
			)
			(layer "F.Fab")
		)
		(fp_line
			(start -0.12065 -0.2794)
			(end 0.12065 -0.2794)
			(stroke
				(width 0.1)
				(type default)
			)
			(layer "F.Fab")
		)
		(fp_line
			(start 0.12065 -0.2794)
			(end 0.12065 -0.3048)
			(stroke
				(width 0.1)
				(type default)
			)
			(layer "F.Fab")
		)
		(fp_line
			(start 0.12065 -0.3048)
			(end 0.67945 -0.3048)
			(stroke
				(width 0.1)
				(type default)
			)
			(layer "F.Fab")
		)
		(fp_line
			(start 0.67945 -0.3048)
			(end 0.67945 0.3048)
			(stroke
				(width 0.1)
				(type default)
			)
			(layer "F.Fab")
		)
		(fp_line
			(start -0.67945 -0.305054)
			(end -0.12065 -0.305054)
			(stroke
				(width 0.1)
				(type default)
			)
			(layer "F.Fab")
		)
		(fp_line
			(start -0.12065 -0.305054)
			(end -0.12065 -0.2794)
			(stroke
				(width 0.1)
				(type default)
			)
			(layer "F.Fab")
		)
		(pad "1" smd circle
			(at -0.40005 0 270)
			(size 0 0)
			(layers "F.Cu" "F.Mask" "F.Paste")
			(net "PVCCFA_EHV_FIVRA_CPU1_EN_R")
		)
		(pad "2" smd circle
			(at 0.40005 0 270)
			(size 0 0)
			(layers "F.Cu" "F.Mask" "F.Paste")
			(net "GND")
		)
	)
)
